FILE_TYPE = CONNECTIVITY;
{Allegro Design Entry HDL 17.4-2019 S026 (4007227) 1/17/2022}
"PAGE_NUMBER" = 429;
0"NC";
1"P5E_CPU0_P3_TX_BUF_C_DN<15:8>";
2"P5E_CPU0_P3_TX_BUF_DN<7:0>";
3"P5E_CPU0_P3_TX_BUF_DP<7:0>";
4"P5E_CPU0_P3_TX_BUF_C_DN<7:0>";
5"P5E_CPU0_P3_TX_BUF_C_DP<7:0>";
6"P5E_CPU0_P3_TX_BUF_DN<15:8>";
7"P5E_CPU0_P3_TX_BUF_DP<15:8>";
8"P5E_CPU0_P3_TX_BUF_C_DP<15:8>";
9"P5E_CPU0_P3_TX_BUF_DN<15:8>";
10"P5E_CPU0_P3_TX_BUF_DP<15:8>";
11"P5E_CPU0_P3_TX_BUF_DN<7:0>";
12"P5E_CPU0_P3_TX_BUF_DP<7:0>";
13"P5E_CPU0_P3_TX_BUF_DP<10>";
14"P5E_CPU0_P3_TX_BUF_DP<13>";
15"P5E_CPU0_P3_TX_BUF_DP<11>";
16"P5E_CPU0_P3_TX_BUF_DP<12>";
17"P5E_CPU0_P3_TX_BUF_DN<13>";
18"P5E_CPU0_P3_TX_BUF_DP<1>";
19"P5E_CPU0_P3_TX_BUF_DP<2>";
20"P5E_CPU0_P3_TX_BUF_DP<5>";
21"P5E_CPU0_P3_TX_BUF_DP<3>";
22"P5E_CPU0_P3_TX_BUF_DN<4>";
23"P5E_CPU0_P3_TX_BUF_DP<7>";
24"P5E_CPU0_P3_TX_BUF_DP<4>";
25"P5E_CPU0_P3_TX_BUF_DN<2>";
26"P5E_CPU0_P3_TX_BUF_DP<14>";
27"P5E_CPU0_P3_TX_BUF_DP<6>";
28"P5E_CPU0_P3_TX_BUF_DP<15>";
29"P5E_CPU0_P3_TX_BUF_DN<7>";
30"P5E_CPU0_P3_TX_BUF_DN<8>";
31"P5E_CPU0_P3_TX_BUF_DN<12>";
32"P5E_CPU0_P3_TX_BUF_DN<14>";
33"P5E_CPU0_P3_TX_BUF_DP<8>";
34"P5E_CPU0_P3_TX_BUF_DN<11>";
35"P5E_CPU0_P3_TX_BUF_DP<0>";
36"P5E_CPU0_P3_TX_BUF_DN<1>";
37"P5E_CPU0_P3_TX_BUF_DN<3>";
38"P5E_CPU0_P3_TX_BUF_DN<0>";
39"P5E_CPU0_P3_TX_BUF_DN<6>";
40"P5E_CPU0_P3_TX_BUF_DN<5>";
41"P5E_CPU0_P3_TX_BUF_DN<15>";
42"P5E_CPU0_P3_TX_BUF_DN<9>";
43"P5E_CPU0_P3_TX_BUF_DP<9>";
44"P5E_CPU0_P3_TX_BUF_DN<10>";
45"P5E_CPU0_P3_TX_BUF_C_DP<8>";
46"P5E_CPU0_P3_TX_BUF_DP<8>";
47"P5E_CPU0_P3_TX_BUF_DN<8>";
48"P5E_CPU0_P3_TX_BUF_C_DN<9>";
49"P5E_CPU0_P3_TX_BUF_C_DP<9>";
50"P5E_CPU0_P3_TX_BUF_C_DP<10>";
51"P5E_CPU0_P3_TX_BUF_C_DN<10>";
52"P5E_CPU0_P3_TX_BUF_C_DN<11>";
53"P5E_CPU0_P3_TX_BUF_C_DP<11>";
54"P5E_CPU0_P3_TX_BUF_C_DP<12>";
55"P5E_CPU0_P3_TX_BUF_C_DN<12>";
56"P5E_CPU0_P3_TX_BUF_C_DP<13>";
57"P5E_CPU0_P3_TX_BUF_C_DN<13>";
58"P5E_CPU0_P3_TX_BUF_C_DP<14>";
59"P5E_CPU0_P3_TX_BUF_C_DN<14>";
60"P5E_CPU0_P3_TX_BUF_C_DP<15>";
61"P5E_CPU0_P3_TX_BUF_C_DN<15>";
62"P5E_CPU0_P3_TX_BUF_DP<9>";
63"P5E_CPU0_P3_TX_BUF_DP<10>";
64"P5E_CPU0_P3_TX_BUF_DN<9>";
65"P5E_CPU0_P3_TX_BUF_DN<10>";
66"P5E_CPU0_P3_TX_BUF_DP<11>";
67"P5E_CPU0_P3_TX_BUF_DP<12>";
68"P5E_CPU0_P3_TX_BUF_DP<13>";
69"P5E_CPU0_P3_TX_BUF_DN<13>";
70"P5E_CPU0_P3_TX_BUF_DN<12>";
71"P5E_CPU0_P3_TX_BUF_DN<11>";
72"P5E_CPU0_P3_TX_BUF_DP<14>";
73"P5E_CPU0_P3_TX_BUF_DP<15>";
74"P5E_CPU0_P3_TX_BUF_DN<14>";
75"P5E_CPU0_P3_TX_BUF_DN<15>";
76"P5E_CPU0_P3_TX_BUF_C_DP<0>";
77"P5E_CPU0_P3_TX_BUF_C_DN<0>";
78"P5E_CPU0_P3_TX_BUF_C_DP<1>";
79"P5E_CPU0_P3_TX_BUF_DP<0>";
80"P5E_CPU0_P3_TX_BUF_DP<1>";
81"P5E_CPU0_P3_TX_BUF_C_DN<1>";
82"P5E_CPU0_P3_TX_BUF_C_DN<2>";
83"P5E_CPU0_P3_TX_BUF_C_DP<2>";
84"P5E_CPU0_P3_TX_BUF_C_DN<3>";
85"P5E_CPU0_P3_TX_BUF_C_DP<3>";
86"P5E_CPU0_P3_TX_BUF_C_DP<4>";
87"P5E_CPU0_P3_TX_BUF_C_DN<4>";
88"P5E_CPU0_P3_TX_BUF_C_DP<5>";
89"P5E_CPU0_P3_TX_BUF_C_DN<6>";
90"P5E_CPU0_P3_TX_BUF_C_DP<6>";
91"P5E_CPU0_P3_TX_BUF_C_DN<5>";
92"P5E_CPU0_P3_TX_BUF_DP<2>";
93"P5E_CPU0_P3_TX_BUF_DP<3>";
94"P5E_CPU0_P3_TX_BUF_DP<5>";
95"P5E_CPU0_P3_TX_BUF_DP<4>";
96"P5E_CPU0_P3_TX_BUF_DP<6>";
97"P5E_CPU0_P3_TX_BUF_DN<0>";
98"P5E_CPU0_P3_TX_BUF_DN<1>";
99"P5E_CPU0_P3_TX_BUF_DN<2>";
100"P5E_CPU0_P3_TX_BUF_DN<3>";
101"P5E_CPU0_P3_TX_BUF_DN<4>";
102"P5E_CPU0_P3_TX_BUF_DN<6>";
103"P5E_CPU0_P3_TX_BUF_DN<5>";
104"P5E_CPU0_P3_TX_BUF_C_DP<7>";
105"P5E_CPU0_P3_TX_BUF_C_DN<7>";
106"P5E_CPU0_P3_TX_BUF_DP<7>";
107"P5E_CPU0_P3_TX_BUF_DN<7>";
108"P5E_CPU0_P3_TX_BUF_C_DN<8>";
%"TAP"
"1","(-3450,1400)","2","standard","I10";
;
CDS_LIB"standard"
BODY_TYPE"PLUMBING"
HDL_TAP"TRUE";
"B \NAC \NWC"2;
"S \NAC"
BN"3"100;
%"Q_CAP_DIFFBUS"
"2","(-7075,1450)","2","pure_quanta","I100";
;
LOCATION"C6619"
$SEC"1"
CDS_SEC"1"
VALUE"DIFF BUS_0.22UF"
CDS_LMAN_SYM_OUTLINE"-25,50,25,-50"
CDS_LIB"pure_quanta"
PIN_NAMES_ROTATE"TRUE"
VOLTAGE"6.3V"
MATERIAL"X6S"
PACK_TYPE"C0201"
TOLERANCE"20%"
PART_NUMBER"SP_CH4221MEE01"
LOCATION"C6619";
"2"
$PN"2"66;
"1"
$PN"1"53;
%"Q_CAP_DIFFBUS"
"2","(-7075,1650)","2","pure_quanta","I101";
;
LOCATION"C6617"
$SEC"1"
CDS_SEC"1"
VALUE"DIFF BUS_0.22UF"
CDS_LMAN_SYM_OUTLINE"-25,50,25,-50"
CDS_LIB"pure_quanta"
PIN_NAMES_ROTATE"TRUE"
VOLTAGE"6.3V"
MATERIAL"X6S"
PACK_TYPE"C0201"
TOLERANCE"20%"
PART_NUMBER"SP_CH4221MEE01"
LOCATION"C6617";
"2"
$PN"2"63;
"1"
$PN"1"50;
%"Q_CAP_DIFFBUS"
"2","(-7075,1850)","2","pure_quanta","I102";
;
LOCATION"C6615"
$SEC"1"
CDS_SEC"1"
VALUE"DIFF BUS_0.22UF"
CDS_LMAN_SYM_OUTLINE"-25,50,25,-50"
CDS_LIB"pure_quanta"
PIN_NAMES_ROTATE"TRUE"
VOLTAGE"6.3V"
MATERIAL"X6S"
PACK_TYPE"C0201"
TOLERANCE"20%"
PART_NUMBER"SP_CH4221MEE01"
LOCATION"C6615";
"2"
$PN"2"62;
"1"
$PN"1"49;
%"Q_CAP_DIFFBUS"
"2","(-7075,1800)","2","pure_quanta","I103";
;
LOCATION"C6616"
$SEC"1"
CDS_SEC"1"
VALUE"DIFF BUS_0.22UF"
CDS_LMAN_SYM_OUTLINE"-25,50,25,-50"
CDS_LIB"pure_quanta"
PIN_NAMES_ROTATE"TRUE"
VOLTAGE"6.3V"
MATERIAL"X6S"
PACK_TYPE"C0201"
TOLERANCE"20%"
PART_NUMBER"SP_CH4221MEE01"
LOCATION"C6616";
"2"
$PN"2"64;
"1"
$PN"1"48;
%"Q_CAP_DIFFBUS"
"2","(-7075,2000)","2","pure_quanta","I104";
;
LOCATION"C6614"
$SEC"1"
CDS_SEC"1"
VALUE"DIFF BUS_0.22UF"
CDS_LMAN_SYM_OUTLINE"-25,50,25,-50"
CDS_LIB"pure_quanta"
PIN_NAMES_ROTATE"TRUE"
VOLTAGE"6.3V"
MATERIAL"X6S"
PACK_TYPE"C0201"
TOLERANCE"20%"
PART_NUMBER"SP_CH4221MEE01"
LOCATION"C6614";
"2"
$PN"2"47;
"1"
$PN"1"108;
%"Q_CAP_DIFFBUS"
"2","(-7075,2050)","2","pure_quanta","I105";
;
LOCATION"C6613"
$SEC"1"
CDS_SEC"1"
PACK_TYPE"C0201"
MATERIAL"X6S"
TOLERANCE"20%"
VALUE"DIFF BUS_0.22UF"
VOLTAGE"6.3V"
CDS_LIB"pure_quanta"
CDS_LMAN_SYM_OUTLINE"-25,50,25,-50"
PIN_NAMES_ROTATE"TRUE"
PART_NUMBER"SP_CH4221MEE01"
LOCATION"C6613";
"2"
$PN"2"46;
"1"
$PN"1"45;
%"TAP"
"1","(-6325,600)","0","standard","I106";
;
CDS_LIB"standard"
BODY_TYPE"PLUMBING"
HDL_TAP"TRUE";
"B \NAC \NWC"1;
"S \NAC"
BN"15"61;
%"TAP"
"1","(-6525,650)","0","standard","I107";
;
CDS_LIB"standard"
BODY_TYPE"PLUMBING"
HDL_TAP"TRUE";
"B \NAC \NWC"8;
"S \NAC"
BN"15"60;
%"TAP"
"1","(-6525,850)","0","standard","I108";
;
CDS_LIB"standard"
BODY_TYPE"PLUMBING"
HDL_TAP"TRUE";
"B \NAC \NWC"8;
"S \NAC"
BN"14"58;
%"TAP"
"1","(-6525,1050)","0","standard","I109";
;
CDS_LIB"standard"
BODY_TYPE"PLUMBING"
HDL_TAP"TRUE";
"B \NAC \NWC"8;
"S \NAC"
BN"13"56;
%"TAP"
"1","(-3200,1250)","2","standard","I11";
;
CDS_LIB"standard"
BODY_TYPE"PLUMBING"
HDL_TAP"TRUE";
"B \NAC \NWC"3;
"S \NAC"
BN"4"95;
%"TAP"
"1","(-6325,800)","0","standard","I110";
;
CDS_LIB"standard"
BODY_TYPE"PLUMBING"
HDL_TAP"TRUE";
"B \NAC \NWC"1;
"S \NAC"
BN"14"59;
%"TAP"
"1","(-6325,1000)","0","standard","I111";
;
CDS_LIB"standard"
BODY_TYPE"PLUMBING"
HDL_TAP"TRUE";
"B \NAC \NWC"1;
"S \NAC"
BN"13"57;
%"TAP"
"1","(-6525,1250)","0","standard","I112";
;
CDS_LIB"standard"
BODY_TYPE"PLUMBING"
HDL_TAP"TRUE";
"B \NAC \NWC"8;
"S \NAC"
BN"12"54;
%"TAP"
"1","(-6525,1450)","0","standard","I113";
;
CDS_LIB"standard"
BODY_TYPE"PLUMBING"
HDL_TAP"TRUE";
"B \NAC \NWC"8;
"S \NAC"
BN"11"53;
%"TAP"
"1","(-6325,1200)","0","standard","I114";
;
CDS_LIB"standard"
BODY_TYPE"PLUMBING"
HDL_TAP"TRUE";
"B \NAC \NWC"1;
"S \NAC"
BN"12"55;
%"TAP"
"1","(-6325,1600)","0","standard","I115";
;
CDS_LIB"standard"
BODY_TYPE"PLUMBING"
HDL_TAP"TRUE";
"B \NAC \NWC"1;
"S \NAC"
BN"10"51;
%"TAP"
"1","(-6325,1400)","0","standard","I116";
;
CDS_LIB"standard"
BODY_TYPE"PLUMBING"
HDL_TAP"TRUE";
"B \NAC \NWC"1;
"S \NAC"
BN"11"52;
%"TAP"
"1","(-6525,1650)","0","standard","I117";
;
CDS_LIB"standard"
BODY_TYPE"PLUMBING"
HDL_TAP"TRUE";
"B \NAC \NWC"8;
"S \NAC"
BN"10"50;
%"TAP"
"1","(-6525,1850)","0","standard","I118";
;
CDS_LIB"standard"
BODY_TYPE"PLUMBING"
HDL_TAP"TRUE";
"B \NAC \NWC"8;
"S \NAC"
BN"9"49;
%"TAP"
"1","(-6525,2050)","0","standard","I119";
;
CDS_LIB"standard"
BODY_TYPE"PLUMBING"
HDL_TAP"TRUE";
"B \NAC \NWC"8;
"S \NAC"
BN"8"45;
%"TAP"
"1","(-3200,1450)","2","standard","I12";
;
CDS_LIB"standard"
BODY_TYPE"PLUMBING"
HDL_TAP"TRUE";
"B \NAC \NWC"3;
"S \NAC"
BN"3"93;
%"TAP"
"1","(-6325,1800)","0","standard","I120";
;
CDS_LIB"standard"
BODY_TYPE"PLUMBING"
HDL_TAP"TRUE";
"B \NAC \NWC"1;
"S \NAC"
BN"9"48;
%"TAP"
"1","(-6325,2000)","0","standard","I121";
;
CDS_LIB"standard"
BODY_TYPE"PLUMBING"
HDL_TAP"TRUE";
"B \NAC \NWC"1;
"S \NAC"
BN"8"108;
%"TAP"
"1","(-1675,3200)","0","standard","I124";
;
CDS_LIB"standard"
BODY_TYPE"PLUMBING"
HDL_TAP"TRUE";
"B \NAC \NWC"11;
"S \NAC"
BN"0"38;
%"TAP"
"1","(-1875,3300)","0","standard","I125";
;
CDS_LIB"standard"
BODY_TYPE"PLUMBING"
HDL_TAP"TRUE";
"B \NAC \NWC"12;
"S \NAC"
BN"0"35;
%"TAP"
"1","(-1875,3650)","0","standard","I126";
;
CDS_LIB"standard"
BODY_TYPE"PLUMBING"
HDL_TAP"TRUE";
"B \NAC \NWC"12;
"S \NAC"
BN"1"18;
%"TAP"
"1","(-1675,3550)","0","standard","I127";
;
CDS_LIB"standard"
BODY_TYPE"PLUMBING"
HDL_TAP"TRUE";
"B \NAC \NWC"11;
"S \NAC"
BN"1"36;
%"TAP"
"1","(-1875,4350)","0","standard","I128";
;
CDS_LIB"standard"
BODY_TYPE"PLUMBING"
HDL_TAP"TRUE";
"B \NAC \NWC"12;
"S \NAC"
BN"3"21;
%"TAP"
"1","(-1875,4700)","0","standard","I129";
;
CDS_LIB"standard"
BODY_TYPE"PLUMBING"
HDL_TAP"TRUE";
"B \NAC \NWC"12;
"S \NAC"
BN"4"24;
%"TAP"
"1","(-3450,1800)","2","standard","I13";
;
CDS_LIB"standard"
BODY_TYPE"PLUMBING"
HDL_TAP"TRUE";
"B \NAC \NWC"2;
"S \NAC"
BN"1"98;
%"TAP"
"1","(-1675,4250)","0","standard","I130";
;
CDS_LIB"standard"
BODY_TYPE"PLUMBING"
HDL_TAP"TRUE";
"B \NAC \NWC"11;
"S \NAC"
BN"3"37;
%"TAP"
"1","(-1675,4600)","0","standard","I131";
;
CDS_LIB"standard"
BODY_TYPE"PLUMBING"
HDL_TAP"TRUE";
"B \NAC \NWC"11;
"S \NAC"
BN"4"22;
%"TAP"
"1","(-1875,5050)","0","standard","I132";
;
CDS_LIB"standard"
BODY_TYPE"PLUMBING"
HDL_TAP"TRUE";
"B \NAC \NWC"12;
"S \NAC"
BN"5"20;
%"TAP"
"1","(-1675,4950)","0","standard","I133";
;
CDS_LIB"standard"
BODY_TYPE"PLUMBING"
HDL_TAP"TRUE";
"B \NAC \NWC"11;
"S \NAC"
BN"5"40;
%"TAP"
"1","(-1875,5400)","0","standard","I134";
;
CDS_LIB"standard"
BODY_TYPE"PLUMBING"
HDL_TAP"TRUE";
"B \NAC \NWC"12;
"S \NAC"
BN"6"27;
%"TAP"
"1","(-1875,5750)","0","standard","I135";
;
CDS_LIB"standard"
BODY_TYPE"PLUMBING"
HDL_TAP"TRUE";
"B \NAC \NWC"12;
"S \NAC"
BN"7"23;
%"TAP"
"1","(-1675,5300)","0","standard","I136";
;
CDS_LIB"standard"
BODY_TYPE"PLUMBING"
HDL_TAP"TRUE";
"B \NAC \NWC"11;
"S \NAC"
BN"6"39;
%"TAP"
"1","(-1675,5650)","0","standard","I137";
;
CDS_LIB"standard"
BODY_TYPE"PLUMBING"
HDL_TAP"TRUE";
"B \NAC \NWC"11;
"S \NAC"
BN"7"29;
%"TAP"
"1","(-3450,2000)","2","standard","I14";
;
CDS_LIB"standard"
BODY_TYPE"PLUMBING"
HDL_TAP"TRUE";
"B \NAC \NWC"2;
"S \NAC"
BN"0"97;
%"TAP"
"1","(-1675,3900)","0","standard","I140";
;
CDS_LIB"standard"
BODY_TYPE"PLUMBING"
HDL_TAP"TRUE";
"B \NAC \NWC"11;
"S \NAC"
BN"2"25;
%"TAP"
"1","(-1875,4000)","0","standard","I141";
;
CDS_LIB"standard"
BODY_TYPE"PLUMBING"
HDL_TAP"TRUE";
"B \NAC \NWC"12;
"S \NAC"
BN"2"19;
%"PT5161LRS"
"11","(-2600,4500)","0","pure_quanta","I142";
;
LOCATION"U6013"
$SEC"11"
CDS_SEC"11"
VALUE"PT5161LRS"
MATERIAL"IC"
PART_TYPE"SMLF"
NEEDS_NO_SIZE"TRUE"
CDS_LMAN_SYM_OUTLINE"-350,1450,300,-1400"
CDS_LIB"pure_quanta"
PART_NUMBER"AJ051610U03";
"B_PETN15"
$PN"EW10"38;
"B_PETP15"
$PN"EU7"35;
"B_PETN14"
$PN"EM10"36;
"B_PETP14"
$PN"EK7"18;
"B_PETN13"
$PN"EE10"25;
"B_PETP13"
$PN"EC7"19;
"B_PETN12"
$PN"DV10"37;
"B_PETP12"
$PN"DT7"21;
"B_PETN11"
$PN"DL10"22;
"B_PETP11"
$PN"DJ7"24;
"B_PETN10"
$PN"DD10"40;
"B_PETP10"
$PN"DB7"20;
"B_PETN9"
$PN"CU10"39;
"B_PETP9"
$PN"CR7"27;
"B_PETN8"
$PN"CK10"29;
"B_PETP8"
$PN"CH7"23;
%"TAP"
"1","(-3450,1600)","2","standard","I15";
;
CDS_LIB"standard"
BODY_TYPE"PLUMBING"
HDL_TAP"TRUE";
"B \NAC \NWC"2;
"S \NAC"
BN"2"99;
%"TAP"
"1","(-3200,1650)","2","standard","I16";
;
CDS_LIB"standard"
BODY_TYPE"PLUMBING"
HDL_TAP"TRUE";
"B \NAC \NWC"3;
"S \NAC"
BN"2"92;
%"TAP"
"1","(-3200,1850)","2","standard","I17";
;
CDS_LIB"standard"
BODY_TYPE"PLUMBING"
HDL_TAP"TRUE";
"B \NAC \NWC"3;
"S \NAC"
BN"1"80;
%"TAP"
"1","(-3200,2050)","2","standard","I18";
;
CDS_LIB"standard"
BODY_TYPE"PLUMBING"
HDL_TAP"TRUE";
"B \NAC \NWC"3;
"S \NAC"
BN"0"79;
%"Q_CAP_DIFFBUS"
"2","(-2475,650)","2","pure_quanta","I19";
;
LOCATION"C6611"
$SEC"1"
CDS_SEC"1"
VALUE"DIFF BUS_0.22UF"
TOLERANCE"20%"
PACK_TYPE"C0201"
MATERIAL"X6S"
VOLTAGE"6.3V"
PIN_NAMES_ROTATE"TRUE"
CDS_LIB"pure_quanta"
CDS_LMAN_SYM_OUTLINE"-25,50,25,-50"
PART_NUMBER"SP_CH4221MEE01"
LOCATION"C6611";
"2"
$PN"2"106;
"1"
$PN"1"104;
%"Q_CAP_DIFFBUS"
"2","(-2475,600)","2","pure_quanta","I20";
;
LOCATION"C6612"
$SEC"1"
CDS_SEC"1"
VALUE"DIFF BUS_0.22UF"
TOLERANCE"20%"
PACK_TYPE"C0201"
MATERIAL"X6S"
VOLTAGE"6.3V"
PIN_NAMES_ROTATE"TRUE"
CDS_LIB"pure_quanta"
CDS_LMAN_SYM_OUTLINE"-25,50,25,-50"
PART_NUMBER"SP_CH4221MEE01"
LOCATION"C6612";
"2"
$PN"2"107;
"1"
$PN"1"105;
%"Q_CAP_DIFFBUS"
"2","(-2475,800)","2","pure_quanta","I21";
;
LOCATION"C6610"
$SEC"1"
CDS_SEC"1"
VALUE"DIFF BUS_0.22UF"
TOLERANCE"20%"
PACK_TYPE"C0201"
MATERIAL"X6S"
VOLTAGE"6.3V"
PIN_NAMES_ROTATE"TRUE"
CDS_LIB"pure_quanta"
CDS_LMAN_SYM_OUTLINE"-25,50,25,-50"
PART_NUMBER"SP_CH4221MEE01"
LOCATION"C6610";
"2"
$PN"2"102;
"1"
$PN"1"89;
%"Q_CAP_DIFFBUS"
"2","(-2475,850)","2","pure_quanta","I22";
;
LOCATION"C6609"
$SEC"1"
CDS_SEC"1"
VALUE"DIFF BUS_0.22UF"
TOLERANCE"20%"
PACK_TYPE"C0201"
MATERIAL"X6S"
VOLTAGE"6.3V"
PIN_NAMES_ROTATE"TRUE"
CDS_LMAN_SYM_OUTLINE"-25,50,25,-50"
CDS_LIB"pure_quanta"
PART_NUMBER"SP_CH4221MEE01"
LOCATION"C6609";
"2"
$PN"2"96;
"1"
$PN"1"90;
%"Q_CAP_DIFFBUS"
"2","(-2475,1000)","2","pure_quanta","I23";
;
LOCATION"C6608"
$SEC"1"
CDS_SEC"1"
VALUE"DIFF BUS_0.22UF"
TOLERANCE"20%"
PACK_TYPE"C0201"
MATERIAL"X6S"
VOLTAGE"6.3V"
PIN_NAMES_ROTATE"TRUE"
CDS_LIB"pure_quanta"
CDS_LMAN_SYM_OUTLINE"-25,50,25,-50"
PART_NUMBER"SP_CH4221MEE01"
LOCATION"C6608";
"2"
$PN"2"103;
"1"
$PN"1"91;
%"Q_CAP_DIFFBUS"
"2","(-2475,1050)","2","pure_quanta","I24";
;
LOCATION"C6607"
$SEC"1"
CDS_SEC"1"
VALUE"DIFF BUS_0.22UF"
TOLERANCE"20%"
PACK_TYPE"C0201"
MATERIAL"X6S"
VOLTAGE"6.3V"
PIN_NAMES_ROTATE"TRUE"
CDS_LIB"pure_quanta"
CDS_LMAN_SYM_OUTLINE"-25,50,25,-50"
PART_NUMBER"SP_CH4221MEE01"
LOCATION"C6607";
"2"
$PN"2"94;
"1"
$PN"1"88;
%"TAP"
"1","(-1925,1050)","0","standard","I25";
;
CDS_LIB"standard"
BODY_TYPE"PLUMBING"
HDL_TAP"TRUE";
"B \NAC \NWC"5;
"S \NAC"
BN"5"88;
%"TAP"
"1","(-1925,850)","0","standard","I26";
;
CDS_LIB"standard"
BODY_TYPE"PLUMBING"
HDL_TAP"TRUE";
"B \NAC \NWC"5;
"S \NAC"
BN"6"90;
%"TAP"
"1","(-1925,650)","0","standard","I27";
;
CDS_LIB"standard"
BODY_TYPE"PLUMBING"
HDL_TAP"TRUE";
"B \NAC \NWC"5;
"S \NAC"
BN"7"104;
%"TAP"
"1","(-1725,800)","0","standard","I28";
;
CDS_LIB"standard"
BODY_TYPE"PLUMBING"
HDL_TAP"TRUE";
"B \NAC \NWC"4;
"S \NAC"
BN"6"89;
%"TAP"
"1","(-1725,600)","0","standard","I29";
;
CDS_LIB"standard"
BODY_TYPE"PLUMBING"
HDL_TAP"TRUE";
"B \NAC \NWC"4;
"S \NAC"
BN"7"105;
%"TAP"
"1","(-3450,1000)","2","standard","I3";
;
CDS_LIB"standard"
BODY_TYPE"PLUMBING"
HDL_TAP"TRUE";
"B \NAC \NWC"2;
"S \NAC"
BN"5"103;
%"TAP"
"1","(-1725,1000)","0","standard","I30";
;
CDS_LIB"standard"
BODY_TYPE"PLUMBING"
HDL_TAP"TRUE";
"B \NAC \NWC"4;
"S \NAC"
BN"5"91;
%"Q_CAP_DIFFBUS"
"2","(-2475,1200)","2","pure_quanta","I31";
;
LOCATION"C6606"
$SEC"1"
CDS_SEC"1"
VALUE"DIFF BUS_0.22UF"
TOLERANCE"20%"
PACK_TYPE"C0201"
MATERIAL"X6S"
VOLTAGE"6.3V"
PIN_NAMES_ROTATE"TRUE"
CDS_LMAN_SYM_OUTLINE"-25,50,25,-50"
CDS_LIB"pure_quanta"
PART_NUMBER"SP_CH4221MEE01"
LOCATION"C6606";
"2"
$PN"2"101;
"1"
$PN"1"87;
%"Q_CAP_DIFFBUS"
"2","(-2475,1250)","2","pure_quanta","I32";
;
LOCATION"C6605"
$SEC"1"
CDS_SEC"1"
VALUE"DIFF BUS_0.22UF"
TOLERANCE"20%"
PACK_TYPE"C0201"
MATERIAL"X6S"
VOLTAGE"6.3V"
PIN_NAMES_ROTATE"TRUE"
CDS_LMAN_SYM_OUTLINE"-25,50,25,-50"
CDS_LIB"pure_quanta"
PART_NUMBER"SP_CH4221MEE01"
LOCATION"C6605";
"2"
$PN"2"95;
"1"
$PN"1"86;
%"Q_CAP_DIFFBUS"
"2","(-2475,1400)","2","pure_quanta","I33";
;
LOCATION"C6604"
$SEC"1"
CDS_SEC"1"
VALUE"DIFF BUS_0.22UF"
TOLERANCE"20%"
PACK_TYPE"C0201"
MATERIAL"X6S"
VOLTAGE"6.3V"
PIN_NAMES_ROTATE"TRUE"
CDS_LIB"pure_quanta"
CDS_LMAN_SYM_OUTLINE"-25,50,25,-50"
PART_NUMBER"SP_CH4221MEE01"
LOCATION"C6604";
"2"
$PN"2"100;
"1"
$PN"1"84;
%"Q_CAP_DIFFBUS"
"2","(-2475,1450)","2","pure_quanta","I34";
;
LOCATION"C6603"
$SEC"1"
CDS_SEC"1"
VALUE"DIFF BUS_0.22UF"
TOLERANCE"20%"
PACK_TYPE"C0201"
MATERIAL"X6S"
VOLTAGE"6.3V"
PIN_NAMES_ROTATE"TRUE"
CDS_LIB"pure_quanta"
CDS_LMAN_SYM_OUTLINE"-25,50,25,-50"
PART_NUMBER"SP_CH4221MEE01"
LOCATION"C6603";
"2"
$PN"2"93;
"1"
$PN"1"85;
%"Q_CAP_DIFFBUS"
"2","(-2475,1600)","2","pure_quanta","I35";
;
LOCATION"C6602"
$SEC"1"
CDS_SEC"1"
VALUE"DIFF BUS_0.22UF"
TOLERANCE"20%"
PACK_TYPE"C0201"
MATERIAL"X6S"
VOLTAGE"6.3V"
PIN_NAMES_ROTATE"TRUE"
CDS_LIB"pure_quanta"
CDS_LMAN_SYM_OUTLINE"-25,50,25,-50"
PART_NUMBER"SP_CH4221MEE01"
LOCATION"C6602";
"2"
$PN"2"99;
"1"
$PN"1"82;
%"Q_CAP_DIFFBUS"
"2","(-2475,1650)","2","pure_quanta","I36";
;
LOCATION"C6601"
$SEC"1"
CDS_SEC"1"
VALUE"DIFF BUS_0.22UF"
TOLERANCE"20%"
PACK_TYPE"C0201"
MATERIAL"X6S"
VOLTAGE"6.3V"
PIN_NAMES_ROTATE"TRUE"
CDS_LIB"pure_quanta"
CDS_LMAN_SYM_OUTLINE"-25,50,25,-50"
PART_NUMBER"SP_CH4221MEE01"
LOCATION"C6601";
"2"
$PN"2"92;
"1"
$PN"1"83;
%"Q_CAP_DIFFBUS"
"2","(-2475,1800)","2","pure_quanta","I37";
;
LOCATION"C6600"
$SEC"1"
CDS_SEC"1"
VALUE"DIFF BUS_0.22UF"
TOLERANCE"20%"
PACK_TYPE"C0201"
MATERIAL"X6S"
VOLTAGE"6.3V"
PIN_NAMES_ROTATE"TRUE"
CDS_LIB"pure_quanta"
CDS_LMAN_SYM_OUTLINE"-25,50,25,-50"
PART_NUMBER"SP_CH4221MEE01"
LOCATION"C6600";
"2"
$PN"2"98;
"1"
$PN"1"81;
%"Q_CAP_DIFFBUS"
"2","(-2475,1850)","2","pure_quanta","I38";
;
LOCATION"C6599"
$SEC"1"
CDS_SEC"1"
VALUE"DIFF BUS_0.22UF"
CDS_LMAN_SYM_OUTLINE"-25,50,25,-50"
CDS_LIB"pure_quanta"
PIN_NAMES_ROTATE"TRUE"
VOLTAGE"6.3V"
MATERIAL"X6S"
PACK_TYPE"C0201"
TOLERANCE"20%"
PART_NUMBER"SP_CH4221MEE01"
LOCATION"C6599";
"2"
$PN"2"80;
"1"
$PN"1"78;
%"Q_CAP_DIFFBUS"
"2","(-2475,2000)","2","pure_quanta","I39";
;
LOCATION"C6598"
$SEC"1"
CDS_SEC"1"
VALUE"DIFF BUS_0.22UF"
TOLERANCE"20%"
PACK_TYPE"C0201"
MATERIAL"X6S"
VOLTAGE"6.3V"
PIN_NAMES_ROTATE"TRUE"
CDS_LIB"pure_quanta"
CDS_LMAN_SYM_OUTLINE"-25,50,25,-50"
PART_NUMBER"SP_CH4221MEE01"
LOCATION"C6598";
"2"
$PN"2"97;
"1"
$PN"1"77;
%"TAP"
"1","(-3450,800)","2","standard","I4";
;
CDS_LIB"standard"
BODY_TYPE"PLUMBING"
HDL_TAP"TRUE";
"B \NAC \NWC"2;
"S \NAC"
BN"6"102;
%"Q_CAP_DIFFBUS"
"2","(-2475,2050)","2","pure_quanta","I40";
;
LOCATION"C6597"
$SEC"1"
CDS_SEC"1"
VALUE"DIFF BUS_0.22UF"
TOLERANCE"20%"
VOLTAGE"6.3V"
MATERIAL"X6S"
PACK_TYPE"C0201"
PIN_NAMES_ROTATE"TRUE"
CDS_LMAN_SYM_OUTLINE"-25,50,25,-50"
CDS_LIB"pure_quanta"
PART_NUMBER"SP_CH4221MEE01"
LOCATION"C6597";
"2"
$PN"2"79;
"1"
$PN"1"76;
%"TAP"
"1","(-1925,1450)","0","standard","I41";
;
CDS_LIB"standard"
BODY_TYPE"PLUMBING"
HDL_TAP"TRUE";
"B \NAC \NWC"5;
"S \NAC"
BN"3"85;
%"TAP"
"1","(-1925,1250)","0","standard","I42";
;
CDS_LIB"standard"
BODY_TYPE"PLUMBING"
HDL_TAP"TRUE";
"B \NAC \NWC"5;
"S \NAC"
BN"4"86;
%"TAP"
"1","(-1725,1200)","0","standard","I43";
;
CDS_LIB"standard"
BODY_TYPE"PLUMBING"
HDL_TAP"TRUE";
"B \NAC \NWC"4;
"S \NAC"
BN"4"87;
%"TAP"
"1","(-1725,1400)","0","standard","I44";
;
CDS_LIB"standard"
BODY_TYPE"PLUMBING"
HDL_TAP"TRUE";
"B \NAC \NWC"4;
"S \NAC"
BN"3"84;
%"TAP"
"1","(-1925,2050)","0","standard","I45";
;
CDS_LIB"standard"
BODY_TYPE"PLUMBING"
HDL_TAP"TRUE";
"B \NAC \NWC"5;
"S \NAC"
BN"0"76;
%"TAP"
"1","(-1925,1850)","0","standard","I46";
;
CDS_LIB"standard"
BODY_TYPE"PLUMBING"
HDL_TAP"TRUE";
"B \NAC \NWC"5;
"S \NAC"
BN"1"78;
%"TAP"
"1","(-1925,1650)","0","standard","I47";
;
CDS_LIB"standard"
BODY_TYPE"PLUMBING"
HDL_TAP"TRUE";
"B \NAC \NWC"5;
"S \NAC"
BN"2"83;
%"TAP"
"1","(-1725,1600)","0","standard","I48";
;
CDS_LIB"standard"
BODY_TYPE"PLUMBING"
HDL_TAP"TRUE";
"B \NAC \NWC"4;
"S \NAC"
BN"2"82;
%"TAP"
"1","(-1725,1800)","0","standard","I49";
;
CDS_LIB"standard"
BODY_TYPE"PLUMBING"
HDL_TAP"TRUE";
"B \NAC \NWC"4;
"S \NAC"
BN"1"81;
%"TAP"
"1","(-3450,600)","2","standard","I5";
;
CDS_LIB"standard"
BODY_TYPE"PLUMBING"
HDL_TAP"TRUE";
"B \NAC \NWC"2;
"S \NAC"
BN"7"107;
%"TAP"
"1","(-1725,2000)","0","standard","I50";
;
CDS_LIB"standard"
BODY_TYPE"PLUMBING"
HDL_TAP"TRUE";
"B \NAC \NWC"4;
"S \NAC"
BN"0"77;
%"PT5161LRS"
"10","(-7775,4525)","0","pure_quanta","I51";
;
LOCATION"U6013"
$SEC"10"
CDS_SEC"10"
VALUE"PT5161LRS"
PART_TYPE"SMLF"
MATERIAL"IC"
CDS_LIB"pure_quanta"
CDS_LMAN_SYM_OUTLINE"-350,1450,300,-1400"
NEEDS_NO_SIZE"TRUE"
PART_NUMBER"AJ051610U03";
"B_PETN7"
$PN"CC10"30;
"B_PETP7"
$PN"CA7"33;
"B_PETN6"
$PN"BT10"42;
"B_PETP6"
$PN"BP7"43;
"B_PETN5"
$PN"BJ10"44;
"B_PETP5"
$PN"BG7"13;
"B_PETN4"
$PN"BB10"34;
"B_PETP4"
$PN"AY7"15;
"B_PETN3"
$PN"AR10"31;
"B_PETP3"
$PN"AN7"16;
"B_PETN2"
$PN"AH10"17;
"B_PETP2"
$PN"AF7"14;
"B_PETN1"
$PN"AA10"32;
"B_PETP1"
$PN"W7"26;
"B_PETN0"
$PN"P10"41;
"B_PETP0"
$PN"M7"28;
%"TAP"
"1","(-7050,3325)","0","standard","I52";
;
CDS_LIB"standard"
BODY_TYPE"PLUMBING"
HDL_TAP"TRUE";
"B \NAC \NWC"10;
"S \NAC"
BN"8"33;
%"TAP"
"1","(-6850,3225)","0","standard","I53";
;
CDS_LIB"standard"
BODY_TYPE"PLUMBING"
HDL_TAP"TRUE";
"B \NAC \NWC"9;
"S \NAC"
BN"8"30;
%"TAP"
"1","(-6850,3575)","0","standard","I54";
;
CDS_LIB"standard"
BODY_TYPE"PLUMBING"
HDL_TAP"TRUE";
"B \NAC \NWC"9;
"S \NAC"
BN"9"42;
%"TAP"
"1","(-7050,3675)","0","standard","I55";
;
CDS_LIB"standard"
BODY_TYPE"PLUMBING"
HDL_TAP"TRUE";
"B \NAC \NWC"10;
"S \NAC"
BN"9"43;
%"TAP"
"1","(-6850,3925)","0","standard","I56";
;
CDS_LIB"standard"
BODY_TYPE"PLUMBING"
HDL_TAP"TRUE";
"B \NAC \NWC"9;
"S \NAC"
BN"10"44;
%"TAP"
"1","(-7050,4025)","0","standard","I57";
;
CDS_LIB"standard"
BODY_TYPE"PLUMBING"
HDL_TAP"TRUE";
"B \NAC \NWC"10;
"S \NAC"
BN"10"13;
%"TAP"
"1","(-3200,650)","2","standard","I6";
;
CDS_LIB"standard"
BODY_TYPE"PLUMBING"
HDL_TAP"TRUE";
"B \NAC \NWC"3;
"S \NAC"
BN"7"106;
%"TAP"
"1","(-7050,4375)","0","standard","I62";
;
CDS_LIB"standard"
BODY_TYPE"PLUMBING"
HDL_TAP"TRUE";
"B \NAC \NWC"10;
"S \NAC"
BN"11"15;
%"TAP"
"1","(-6850,4275)","0","standard","I63";
;
CDS_LIB"standard"
BODY_TYPE"PLUMBING"
HDL_TAP"TRUE";
"B \NAC \NWC"9;
"S \NAC"
BN"11"34;
%"TAP"
"1","(-6850,4625)","0","standard","I64";
;
CDS_LIB"standard"
BODY_TYPE"PLUMBING"
HDL_TAP"TRUE";
"B \NAC \NWC"9;
"S \NAC"
BN"12"31;
%"TAP"
"1","(-7050,4725)","0","standard","I65";
;
CDS_LIB"standard"
BODY_TYPE"PLUMBING"
HDL_TAP"TRUE";
"B \NAC \NWC"10;
"S \NAC"
BN"12"16;
%"TAP"
"1","(-6850,4975)","0","standard","I66";
;
CDS_LIB"standard"
BODY_TYPE"PLUMBING"
HDL_TAP"TRUE";
"B \NAC \NWC"9;
"S \NAC"
BN"13"17;
%"TAP"
"1","(-7050,5075)","0","standard","I67";
;
CDS_LIB"standard"
BODY_TYPE"PLUMBING"
HDL_TAP"TRUE";
"B \NAC \NWC"10;
"S \NAC"
BN"13"14;
%"TAP"
"1","(-7050,5425)","0","standard","I68";
;
CDS_LIB"standard"
BODY_TYPE"PLUMBING"
HDL_TAP"TRUE";
"B \NAC \NWC"10;
"S \NAC"
BN"14"26;
%"TAP"
"1","(-6850,5325)","0","standard","I69";
;
CDS_LIB"standard"
BODY_TYPE"PLUMBING"
HDL_TAP"TRUE";
"B \NAC \NWC"9;
"S \NAC"
BN"14"32;
%"TAP"
"1","(-3200,850)","2","standard","I7";
;
CDS_LIB"standard"
BODY_TYPE"PLUMBING"
HDL_TAP"TRUE";
"B \NAC \NWC"3;
"S \NAC"
BN"6"96;
%"TAP"
"1","(-7050,5775)","0","standard","I70";
;
CDS_LIB"standard"
BODY_TYPE"PLUMBING"
HDL_TAP"TRUE";
"B \NAC \NWC"10;
"S \NAC"
BN"15"28;
%"TAP"
"1","(-6850,5675)","0","standard","I71";
;
CDS_LIB"standard"
BODY_TYPE"PLUMBING"
HDL_TAP"TRUE";
"B \NAC \NWC"9;
"S \NAC"
BN"15"41;
%"TAP"
"1","(-8050,600)","2","standard","I74";
;
CDS_LIB"standard"
BODY_TYPE"PLUMBING"
HDL_TAP"TRUE";
"B \NAC \NWC"6;
"S \NAC"
BN"15"75;
%"TAP"
"1","(-8050,800)","2","standard","I75";
;
CDS_LIB"standard"
BODY_TYPE"PLUMBING"
HDL_TAP"TRUE";
"B \NAC \NWC"6;
"S \NAC"
BN"14"74;
%"TAP"
"1","(-8050,1000)","2","standard","I76";
;
CDS_LIB"standard"
BODY_TYPE"PLUMBING"
HDL_TAP"TRUE";
"B \NAC \NWC"6;
"S \NAC"
BN"13"69;
%"TAP"
"1","(-7800,650)","2","standard","I77";
;
CDS_LIB"standard"
BODY_TYPE"PLUMBING"
HDL_TAP"TRUE";
"B \NAC \NWC"7;
"S \NAC"
BN"15"73;
%"TAP"
"1","(-7800,850)","2","standard","I78";
;
CDS_LIB"standard"
BODY_TYPE"PLUMBING"
HDL_TAP"TRUE";
"B \NAC \NWC"7;
"S \NAC"
BN"14"72;
%"TAP"
"1","(-7800,1050)","2","standard","I79";
;
CDS_LIB"standard"
BODY_TYPE"PLUMBING"
HDL_TAP"TRUE";
"B \NAC \NWC"7;
"S \NAC"
BN"13"68;
%"TAP"
"1","(-3200,1050)","2","standard","I8";
;
CDS_LIB"standard"
BODY_TYPE"PLUMBING"
HDL_TAP"TRUE";
"B \NAC \NWC"3;
"S \NAC"
BN"5"94;
%"TAP"
"1","(-8050,1200)","2","standard","I80";
;
CDS_LIB"standard"
BODY_TYPE"PLUMBING"
HDL_TAP"TRUE";
"B \NAC \NWC"6;
"S \NAC"
BN"12"70;
%"TAP"
"1","(-8050,1400)","2","standard","I81";
;
CDS_LIB"standard"
BODY_TYPE"PLUMBING"
HDL_TAP"TRUE";
"B \NAC \NWC"6;
"S \NAC"
BN"11"71;
%"TAP"
"1","(-8050,1600)","2","standard","I82";
;
CDS_LIB"standard"
BODY_TYPE"PLUMBING"
HDL_TAP"TRUE";
"B \NAC \NWC"6;
"S \NAC"
BN"10"65;
%"TAP"
"1","(-7800,1250)","2","standard","I83";
;
CDS_LIB"standard"
BODY_TYPE"PLUMBING"
HDL_TAP"TRUE";
"B \NAC \NWC"7;
"S \NAC"
BN"12"67;
%"TAP"
"1","(-7800,1450)","2","standard","I84";
;
CDS_LIB"standard"
BODY_TYPE"PLUMBING"
HDL_TAP"TRUE";
"B \NAC \NWC"7;
"S \NAC"
BN"11"66;
%"TAP"
"1","(-8050,1800)","2","standard","I85";
;
CDS_LIB"standard"
BODY_TYPE"PLUMBING"
HDL_TAP"TRUE";
"B \NAC \NWC"6;
"S \NAC"
BN"9"64;
%"TAP"
"1","(-8050,2000)","2","standard","I86";
;
CDS_LIB"standard"
BODY_TYPE"PLUMBING"
HDL_TAP"TRUE";
"B \NAC \NWC"6;
"S \NAC"
BN"8"47;
%"TAP"
"1","(-7800,1650)","2","standard","I87";
;
CDS_LIB"standard"
BODY_TYPE"PLUMBING"
HDL_TAP"TRUE";
"B \NAC \NWC"7;
"S \NAC"
BN"10"63;
%"TAP"
"1","(-7800,1850)","2","standard","I88";
;
CDS_LIB"standard"
BODY_TYPE"PLUMBING"
HDL_TAP"TRUE";
"B \NAC \NWC"7;
"S \NAC"
BN"9"62;
%"TAP"
"1","(-7800,2050)","2","standard","I89";
;
CDS_LIB"standard"
BODY_TYPE"PLUMBING"
HDL_TAP"TRUE";
"B \NAC \NWC"7;
"S \NAC"
BN"8"46;
%"TAP"
"1","(-3450,1200)","2","standard","I9";
;
CDS_LIB"standard"
BODY_TYPE"PLUMBING"
HDL_TAP"TRUE";
"B \NAC \NWC"2;
"S \NAC"
BN"4"101;
%"Q_CAP_DIFFBUS"
"2","(-7075,600)","2","pure_quanta","I90";
;
LOCATION"C6628"
$SEC"1"
CDS_SEC"1"
VALUE"DIFF BUS_0.22UF"
CDS_LMAN_SYM_OUTLINE"-25,50,25,-50"
CDS_LIB"pure_quanta"
PIN_NAMES_ROTATE"TRUE"
VOLTAGE"6.3V"
MATERIAL"X6S"
PACK_TYPE"C0201"
TOLERANCE"20%"
PART_NUMBER"SP_CH4221MEE01"
LOCATION"C6628";
"2"
$PN"2"75;
"1"
$PN"1"61;
%"Q_CAP_DIFFBUS"
"2","(-7075,850)","2","pure_quanta","I91";
;
LOCATION"C6625"
$SEC"1"
CDS_SEC"1"
VALUE"DIFF BUS_0.22UF"
CDS_LIB"pure_quanta"
CDS_LMAN_SYM_OUTLINE"-25,50,25,-50"
PIN_NAMES_ROTATE"TRUE"
VOLTAGE"6.3V"
MATERIAL"X6S"
PACK_TYPE"C0201"
TOLERANCE"20%"
PART_NUMBER"SP_CH4221MEE01"
LOCATION"C6625";
"2"
$PN"2"72;
"1"
$PN"1"58;
%"Q_CAP_DIFFBUS"
"2","(-7075,800)","2","pure_quanta","I92";
;
LOCATION"C6626"
$SEC"1"
CDS_SEC"1"
VALUE"DIFF BUS_0.22UF"
CDS_LMAN_SYM_OUTLINE"-25,50,25,-50"
CDS_LIB"pure_quanta"
PIN_NAMES_ROTATE"TRUE"
VOLTAGE"6.3V"
MATERIAL"X6S"
PACK_TYPE"C0201"
TOLERANCE"20%"
PART_NUMBER"SP_CH4221MEE01"
LOCATION"C6626";
"2"
$PN"2"74;
"1"
$PN"1"59;
%"Q_CAP_DIFFBUS"
"2","(-7075,650)","2","pure_quanta","I93";
;
LOCATION"C6627"
$SEC"1"
CDS_SEC"1"
VALUE"DIFF BUS_0.22UF"
CDS_LMAN_SYM_OUTLINE"-25,50,25,-50"
CDS_LIB"pure_quanta"
PIN_NAMES_ROTATE"TRUE"
VOLTAGE"6.3V"
MATERIAL"X6S"
PACK_TYPE"C0201"
TOLERANCE"20%"
PART_NUMBER"SP_CH4221MEE01"
LOCATION"C6627";
"2"
$PN"2"73;
"1"
$PN"1"60;
%"Q_CAP_DIFFBUS"
"2","(-7075,1050)","2","pure_quanta","I94";
;
LOCATION"C6623"
$SEC"1"
CDS_SEC"1"
VALUE"DIFF BUS_0.22UF"
CDS_LMAN_SYM_OUTLINE"-25,50,25,-50"
CDS_LIB"pure_quanta"
PIN_NAMES_ROTATE"TRUE"
VOLTAGE"6.3V"
MATERIAL"X6S"
PACK_TYPE"C0201"
TOLERANCE"20%"
PART_NUMBER"SP_CH4221MEE01"
LOCATION"C6623";
"2"
$PN"2"68;
"1"
$PN"1"56;
%"Q_CAP_DIFFBUS"
"2","(-7075,1000)","2","pure_quanta","I95";
;
LOCATION"C6624"
$SEC"1"
CDS_SEC"1"
VALUE"DIFF BUS_0.22UF"
CDS_LMAN_SYM_OUTLINE"-25,50,25,-50"
CDS_LIB"pure_quanta"
PIN_NAMES_ROTATE"TRUE"
VOLTAGE"6.3V"
MATERIAL"X6S"
PACK_TYPE"C0201"
TOLERANCE"20%"
PART_NUMBER"SP_CH4221MEE01"
LOCATION"C6624";
"2"
$PN"2"69;
"1"
$PN"1"57;
%"Q_CAP_DIFFBUS"
"2","(-7075,1250)","2","pure_quanta","I96";
;
LOCATION"C6621"
$SEC"1"
CDS_SEC"1"
VALUE"DIFF BUS_0.22UF"
CDS_LIB"pure_quanta"
CDS_LMAN_SYM_OUTLINE"-25,50,25,-50"
PIN_NAMES_ROTATE"TRUE"
VOLTAGE"6.3V"
MATERIAL"X6S"
PACK_TYPE"C0201"
TOLERANCE"20%"
PART_NUMBER"SP_CH4221MEE01"
LOCATION"C6621";
"2"
$PN"2"67;
"1"
$PN"1"54;
%"Q_CAP_DIFFBUS"
"2","(-7075,1200)","2","pure_quanta","I97";
;
LOCATION"C6622"
$SEC"1"
CDS_SEC"1"
VALUE"DIFF BUS_0.22UF"
CDS_LIB"pure_quanta"
CDS_LMAN_SYM_OUTLINE"-25,50,25,-50"
PIN_NAMES_ROTATE"TRUE"
VOLTAGE"6.3V"
MATERIAL"X6S"
PACK_TYPE"C0201"
TOLERANCE"20%"
PART_NUMBER"SP_CH4221MEE01"
LOCATION"C6622";
"2"
$PN"2"70;
"1"
$PN"1"55;
%"Q_CAP_DIFFBUS"
"2","(-7075,1400)","2","pure_quanta","I98";
;
LOCATION"C6620"
$SEC"1"
CDS_SEC"1"
VALUE"DIFF BUS_0.22UF"
CDS_LMAN_SYM_OUTLINE"-25,50,25,-50"
CDS_LIB"pure_quanta"
PIN_NAMES_ROTATE"TRUE"
VOLTAGE"6.3V"
MATERIAL"X6S"
PACK_TYPE"C0201"
TOLERANCE"20%"
PART_NUMBER"SP_CH4221MEE01"
LOCATION"C6620";
"2"
$PN"2"71;
"1"
$PN"1"52;
%"Q_CAP_DIFFBUS"
"2","(-7075,1600)","2","pure_quanta","I99";
;
LOCATION"C6618"
$SEC"1"
CDS_SEC"1"
VALUE"DIFF BUS_0.22UF"
CDS_LMAN_SYM_OUTLINE"-25,50,25,-50"
CDS_LIB"pure_quanta"
PIN_NAMES_ROTATE"TRUE"
VOLTAGE"6.3V"
MATERIAL"X6S"
PACK_TYPE"C0201"
TOLERANCE"20%"
PART_NUMBER"SP_CH4221MEE01"
LOCATION"C6618";
"2"
$PN"2"65;
"1"
$PN"1"51;
END.
